# BASEBOARD_FAB2 (Tioga Pass) — schematic netlist excerpt (pin names and nets, part order shuffled) for the footprints in the layout excerpt that follows; sources: Cadence DE-HDL packaged netlist, KiCad conversion of Wiwynn_Tioga_Pass_MB.brd

CF24  SC22P50V2JN-4GP  5%  pkg SMD-BCG  page 235 : \1\ = VR_P1V05_PCH_BIREF1 ; \2\ = ISENSE_P1V05_PCH_STBY_PH1_IMON
R3W9  RES  10.0K 1% CHIP  pkg 0402  page 249 : A = VREF_2V2 ; B = GND
C5G73  CAP_A  22.0UF 4V 20% X6S  pkg 0603V  page 242 : A = PVDDQ_DEF ; B = GND

(kicad_pcb
	(version 20260206)
	(generator "pcbnew")
	(generator_version "10.0")
	(general
		(thickness 1.6)
		(legacy_teardrops no)
	)
	(paper "A4")
	(title_block
		(title "Wiwynn_Tioga_Pass_MB.brd")
		(comment 1 "Tioga Pass / footprints 3544-3546 of 4770")
	)
	(layers
		(0 "F.Cu" signal "TOP")
		(4 "In1.Cu" signal "L2GND")
		(6 "In2.Cu" signal "L3")
		(8 "In3.Cu" signal "L4GND")
		(10 "In4.Cu" signal "L5")
		(12 "In5.Cu" signal "L6GND")
		(14 "In6.Cu" signal "L7VCC")
		(16 "In7.Cu" signal "L8VCC")
		(18 "In8.Cu" signal "L9GND")
		(20 "In9.Cu" signal "L10")
		(22 "In10.Cu" signal "L11GND")
		(24 "In11.Cu" signal "L12")
		(26 "In12.Cu" signal "L13GND")
		(2 "B.Cu" signal "BOTTOM")
		(9 "F.Adhes" user "F.Adhesive")
		(11 "B.Adhes" user "B.Adhesive")
		(13 "F.Paste" user "Package Geometry/Pastemask Top")
		(15 "B.Paste" user "Package Geometry/Pastemask Bottom")
		(5 "F.SilkS" user "Ref Des/Silkscreen Top")
		(7 "B.SilkS" user "Ref Des/Silkscreen Bottom")
		(1 "F.Mask" user "Board Geometry/Soldermask Top")
		(3 "B.Mask" user "Board Geometry/Soldermask Bottom")
		(17 "Dwgs.User" user "User.Drawings")
		(19 "Cmts.User" user "User.Comments")
		(21 "Eco1.User" user "User.Eco1")
		(23 "Eco2.User" user "User.Eco2")
		(25 "Edge.Cuts" user "Board Geometry/Outline")
		(27 "Margin" user)
		(31 "F.CrtYd" user "Package Geometry/Place Bound Top")
		(29 "B.CrtYd" user "Package Geometry/Place Bound Bottom")
		(35 "F.Fab" user "Ref Des/Assembly Top")
		(33 "B.Fab" user "Ref Des/Assembly Bottom")
	)
	(footprint ""
		(layer "B.Cu")
		(at 447.9036 -18.1102 -90)
		(property "Reference" "R3W9"
			(at 0.8382 -0.67818 270)
			(unlocked yes)
			(layer "B.SilkS")
			(effects
				(font
					(size 0.4064 0.254)
					(thickness 0.1524)
				)
				(justify left mirror)
			)
		)
		(property "Value" ""
			(at 0 0 90)
			(layer "B.Fab")
			(effects
				(font
					(size 1.27 1.27)
				)
				(justify mirror)
			)
		)
		(duplicate_pad_numbers_are_jumpers no)
		(fp_poly
			(pts
				(xy 0.2794 -0.1016) (xy -0.2794 -0.1016) (xy -0.2794 0.9906) (xy 0.2794 0.9906)
			)
			(stroke
				(width 0)
				(type default)
			)
			(fill no)
			(layer "B.CrtYd")
		)
		(fp_line
			(start -0.2794 0.9906)
			(end -0.2794 -0.1016)
			(stroke
				(width 0.1)
				(type default)
			)
			(layer "B.Fab")
		)
		(fp_line
			(start 0.2794 0.9906)
			(end -0.2794 0.9906)
			(stroke
				(width 0.1)
				(type default)
			)
			(layer "B.Fab")
		)
		(fp_line
			(start -0.2794 -0.1016)
			(end 0.2794 -0.1016)
			(stroke
				(width 0.1)
				(type default)
			)
			(layer "B.Fab")
		)
		(fp_line
			(start 0.2794 -0.1016)
			(end 0.2794 0.9906)
			(stroke
				(width 0.1)
				(type default)
			)
			(layer "B.Fab")
		)
		(pad "1" smd rect
			(at 0 0 90)
			(size 0.508 0.508)
			(layers "B.Cu" "B.Mask" "B.Paste")
			(net "VREF_2V2")
		)
		(pad "2" smd rect
			(at 0 0.889 90)
			(size 0.508 0.508)
			(layers "B.Cu" "B.Mask" "B.Paste")
			(net "GND")
		)
		(zone
			(layer "B.Cu")
			(hatch none 0.5)
			(connect_pads
				(clearance 0)
			)
			(min_thickness 0.25)
			(keepout
				(tracks not_allowed)
				(vias allowed)
				(pads allowed)
				(copperpour not_allowed)
				(footprints allowed)
			)
			(placement
				(enabled no)
				(sheetname "")
			)
			(fill
				(thermal_gap 0.5)
				(thermal_bridge_width 0.5)
				(island_removal_mode 0)
			)
			(polygon
				(pts
					(xy 447.2686 -17.8562) (xy 447.2686 -18.3642) (xy 447.6496 -18.3642) (xy 447.6496 -17.8562)
				)
			)
		)
		(zone
			(layer "B.Cu")
			(hatch none 0.5)
			(connect_pads
				(clearance 0)
			)
			(min_thickness 0.25)
			(keepout
				(tracks allowed)
				(vias not_allowed)
				(pads allowed)
				(copperpour not_allowed)
				(footprints allowed)
			)
			(placement
				(enabled no)
				(sheetname "")
			)
			(fill
				(thermal_gap 0.5)
				(thermal_bridge_width 0.5)
				(island_removal_mode 0)
			)
			(polygon
				(pts
					(xy 447.6496 -17.8562) (xy 447.6496 -18.3642) (xy 447.2686 -18.3642) (xy 447.2686 -17.8562)
				)
			)
		)
	)
	(footprint ""
		(layer "B.Cu")
		(at 266.397232 -140.208 90)
		(property "Reference" "C5G73"
			(at -1.14681 0.76708 180)
			(unlocked yes)
			(layer "B.SilkS")
			(effects
				(font
					(size 0.7874 0.5842)
					(thickness 0.1524)
				)
				(justify mirror)
			)
		)
		(property "Value" ""
			(at 0 0 90)
			(layer "B.Fab")
			(effects
				(font
					(size 1.27 1.27)
				)
				(justify mirror)
			)
		)
		(duplicate_pad_numbers_are_jumpers no)
		(fp_rect
			(start -0.4953 -0.2032)
			(end 0.4953 1.6002)
			(stroke
				(width 0)
				(type default)
			)
			(fill no)
			(layer "B.CrtYd")
		)
		(fp_line
			(start 0.4953 -0.2032)
			(end -0.4953 -0.2032)
			(stroke
				(width 0.1)
				(type default)
			)
			(layer "B.Fab")
		)
		(fp_line
			(start -0.4953 -0.2032)
			(end -0.4953 1.6002)
			(stroke
				(width 0.1)
				(type default)
			)
			(layer "B.Fab")
		)
		(fp_line
			(start 0.4953 1.6002)
			(end 0.4953 -0.2032)
			(stroke
				(width 0.1)
				(type default)
			)
			(layer "B.Fab")
		)
		(fp_line
			(start -0.4953 1.6002)
			(end 0.4953 1.6002)
			(stroke
				(width 0.1)
				(type default)
			)
			(layer "B.Fab")
		)
		(pad "1" smd rect
			(at 0 0 270)
			(size 0.762 0.889)
			(layers "B.Cu" "B.Mask" "B.Paste")
			(net "PVDDQ_DEF")
		)
		(pad "2" smd rect
			(at 0 1.397 270)
			(size 0.762 0.889)
			(layers "B.Cu" "B.Mask" "B.Paste")
			(net "GND")
		)
		(zone
			(layer "B.Cu")
			(hatch none 0.5)
			(connect_pads
				(clearance 0)
			)
			(min_thickness 0.25)
			(keepout
				(tracks not_allowed)
				(vias allowed)
				(pads allowed)
				(copperpour not_allowed)
				(footprints allowed)
			)
			(placement
				(enabled no)
				(sheetname "")
			)
			(fill
				(thermal_gap 0.5)
				(thermal_bridge_width 0.5)
				(island_removal_mode 0)
			)
			(polygon
				(pts
					(xy 266.841732 -139.827) (xy 267.349732 -139.827) (xy 267.349732 -140.589) (xy 266.841732 -140.589)
				)
			)
		)
	)
	(footprint ""
		(layer "B.Cu")
		(at 396.018766 -157.117288 -90)
		(property "Reference" "CF24"
			(at 0 0 90)
			(layer "B.SilkS")
			(hide yes)
			(effects
				(font
					(size 1.27 1.27)
				)
				(justify mirror)
			)
		)
		(property "Value" "*"
			(at -1.1811 -2.8194 270)
			(unlocked yes)
			(layer "B.Fab")
			(hide yes)
			(effects
				(font
					(size 1.27 1.016)
					(thickness 0.1524)
				)
				(justify mirror)
			)
		)
		(property "Device Type" "SC22P50V2JN-4GP_SMD-BCG-SC22P5A"
			(at -1.1811 -4.3434 270)
			(unlocked yes)
			(layer "B.Fab")
			(hide yes)
			(effects
				(font
					(size 1.27 1.016)
					(thickness 0.1524)
				)
				(justify mirror)
			)
		)
		(duplicate_pad_numbers_are_jumpers no)
		(fp_rect
			(start 0.4318 0.9525)
			(end -0.4318 -0.9525)
			(stroke
				(width 0)
				(type default)
			)
			(fill no)
			(layer "B.CrtYd")
		)
		(fp_rect
			(start 0.4318 0.9525)
			(end -0.4318 -0.9525)
			(stroke
				(width 0)
				(type default)
			)
			(fill no)
			(layer "B.Fab")
		)
		(pad "1" smd custom
			(at 0 -0.4445 90)
			(size 0.1524 0.1524)
			(layers "B.Cu" "B.Mask" "B.Paste")
			(net "VR_P1V05_PCH_BIREF1")
			(options
				(clearance outline)
				(anchor circle)
			)
			(primitives
				(gr_poly
					(pts
						(arc
							(start 0.3048 0.2032)
							(mid 0.275042 0.275042)
							(end 0.2032 0.3048)
						)
						(arc
							(start -0.2032 0.3048)
							(mid -0.275042 0.275042)
							(end -0.3048 0.2032)
						)
						(arc
							(start -0.3048 -0.2032)
							(mid -0.275042 -0.275042)
							(end -0.2032 -0.3048)
						)
						(arc
							(start 0.2032 -0.3048)
							(mid 0.275042 -0.275042)
							(end 0.3048 -0.2032)
						)
					)
					(width 0)
					(fill yes)
				)
			)
		)
		(pad "2" smd custom
			(at 0 0.4445 90)
			(size 0.1524 0.1524)
			(layers "B.Cu" "B.Mask" "B.Paste")
			(net "ISENSE_P1V05_PCH_STBY_PH1_IMON")
			(options
				(clearance outline)
				(anchor circle)
			)
			(primitives
				(gr_poly
					(pts
						(arc
							(start 0.3048 0.2032)
							(mid 0.275042 0.275042)
							(end 0.2032 0.3048)
						)
						(arc
							(start -0.2032 0.3048)
							(mid -0.275042 0.275042)
							(end -0.3048 0.2032)
						)
						(arc
							(start -0.3048 -0.2032)
							(mid -0.275042 -0.275042)
							(end -0.2032 -0.3048)
						)
						(arc
							(start 0.2032 -0.3048)
							(mid 0.275042 -0.275042)
							(end 0.3048 -0.2032)
						)
					)
					(width 0)
					(fill yes)
				)
			)
		)
	)
)
